(kicad_pcb
	(version 20260206)
	(generator "pcbnew")
	(generator_version "10.0")
	(general
		(thickness 1.6)
		(legacy_teardrops no)
	)
	(paper "A4")
	(title_block
		(title "9054_F0T_PDB_BD_GPU_F_V04_1213_1550_OCP.brd")
		(comment 1 "Grand Teton / footprints 119-123 of 608")
	)
	(layers
		(0 "F.Cu" signal "TOP")
		(4 "In1.Cu" signal "GND")
		(6 "In2.Cu" signal "IN1")
		(8 "In3.Cu" signal "GND1")
		(10 "In4.Cu" signal "VCC")
		(12 "In5.Cu" signal "VCC1")
		(14 "In6.Cu" signal "GND2")
		(16 "In7.Cu" signal "IN2")
		(18 "In8.Cu" signal "GND3")
		(2 "B.Cu" signal "BOTTOM")
		(9 "F.Adhes" user "F.Adhesive")
		(11 "B.Adhes" user "B.Adhesive")
		(13 "F.Paste" user "Package Geometry/Pastemask Top")
		(15 "B.Paste" user "Package Geometry/Pastemask Bottom")
		(5 "F.SilkS" user "Ref Des/Silkscreen Top")
		(7 "B.SilkS" user "Ref Des/Silkscreen Bottom")
		(1 "F.Mask" user "Board Geometry/Soldermask Top")
		(3 "B.Mask" user "Board Geometry/Soldermask Bottom")
		(17 "Dwgs.User" user "User.Drawings")
		(19 "Cmts.User" user "User.Comments")
		(21 "Eco1.User" user "User.Eco1")
		(23 "Eco2.User" user "User.Eco2")
		(25 "Edge.Cuts" user "Board Geometry/Outline")
		(27 "Margin" user)
		(31 "F.CrtYd" user "Package Geometry/Place Bound Top")
		(29 "B.CrtYd" user "Package Geometry/Place Bound Bottom")
		(35 "F.Fab" user "Ref Des/Assembly Top")
		(33 "B.Fab" user "Ref Des/Assembly Bottom")
	)
	(footprint ""
		(layer "F.Cu")
		(at 442.595 -37.465)
		(property "Reference" "U2"
			(at -4.1148 -1.99263 0)
			(unlocked yes)
			(layer "F.SilkS")
			(effects
				(font
					(size 0.7874 0.5842)
					(thickness 0.1524)
				)
				(justify left)
			)
		)
		(property "Value" ""
			(at 0 0 0)
			(layer "F.Fab")
			(effects
				(font
					(size 1.27 1.27)
				)
			)
		)
		(duplicate_pad_numbers_are_jumpers no)
		(fp_line
			(start -1.3716 -1.524)
			(end -0.508 -1.524)
			(stroke
				(width 0.1524)
				(type default)
			)
			(layer "F.SilkS")
		)
		(fp_line
			(start -1.3716 1.524)
			(end -1.3716 -1.524)
			(stroke
				(width 0.1524)
				(type default)
			)
			(layer "F.SilkS")
		)
		(fp_line
			(start -0.508 -1.524)
			(end 0 -1.016)
			(stroke
				(width 0.1524)
				(type default)
			)
			(layer "F.SilkS")
		)
		(fp_line
			(start 0 -1.016)
			(end 0.508 -1.524)
			(stroke
				(width 0.1524)
				(type default)
			)
			(layer "F.SilkS")
		)
		(fp_line
			(start 0.508 -1.524)
			(end 1.3716 -1.524)
			(stroke
				(width 0.1524)
				(type default)
			)
			(layer "F.SilkS")
		)
		(fp_line
			(start 1.3716 -1.524)
			(end 1.3716 1.524)
			(stroke
				(width 0.1524)
				(type default)
			)
			(layer "F.SilkS")
		)
		(fp_line
			(start 1.3716 1.524)
			(end -1.3716 1.524)
			(stroke
				(width 0.1524)
				(type default)
			)
			(layer "F.SilkS")
		)
		(fp_poly
			(pts
				(xy -2.684272 -1.84912) (xy -2.059432 -1.84912) (xy -2.3876 -1.2954)
			)
			(stroke
				(width 0)
				(type default)
			)
			(fill yes)
			(layer "F.SilkS")
		)
		(fp_line
			(start -2.54 -1.0668)
			(end -1.5494 -1.0668)
			(stroke
				(width 0.1)
				(type default)
			)
			(layer "F.Fab")
		)
		(fp_line
			(start -2.54 1.0668)
			(end -2.54 -1.0668)
			(stroke
				(width 0.1)
				(type default)
			)
			(layer "F.Fab")
		)
		(fp_line
			(start -1.5494 -1.524)
			(end 1.5494 -1.524)
			(stroke
				(width 0.1)
				(type default)
			)
			(layer "F.Fab")
		)
		(fp_line
			(start -1.5494 -1.0668)
			(end -1.5494 -1.524)
			(stroke
				(width 0.1)
				(type default)
			)
			(layer "F.Fab")
		)
		(fp_line
			(start -1.5494 1.0668)
			(end -2.54 1.0668)
			(stroke
				(width 0.1)
				(type default)
			)
			(layer "F.Fab")
		)
		(fp_line
			(start -1.5494 1.0668)
			(end -1.5494 -1.0668)
			(stroke
				(width 0.1)
				(type default)
			)
			(layer "F.Fab")
		)
		(fp_line
			(start -1.5494 1.524)
			(end -1.5494 1.0668)
			(stroke
				(width 0.1)
				(type default)
			)
			(layer "F.Fab")
		)
		(fp_line
			(start 1.5494 -1.524)
			(end 1.5494 -1.0668)
			(stroke
				(width 0.1)
				(type default)
			)
			(layer "F.Fab")
		)
		(fp_line
			(start 1.5494 -1.0668)
			(end 1.5494 1.0668)
			(stroke
				(width 0.1)
				(type default)
			)
			(layer "F.Fab")
		)
		(fp_line
			(start 1.5494 -1.0668)
			(end 2.54 -1.0668)
			(stroke
				(width 0.1)
				(type default)
			)
			(layer "F.Fab")
		)
		(fp_line
			(start 1.5494 1.0668)
			(end 1.5494 1.524)
			(stroke
				(width 0.1)
				(type default)
			)
			(layer "F.Fab")
		)
		(fp_line
			(start 1.5494 1.524)
			(end -1.5494 1.524)
			(stroke
				(width 0.1)
				(type default)
			)
			(layer "F.Fab")
		)
		(fp_line
			(start 2.54 -1.0668)
			(end 2.54 1.0668)
			(stroke
				(width 0.1)
				(type default)
			)
			(layer "F.Fab")
		)
		(fp_line
			(start 2.54 1.0668)
			(end 1.5494 1.0668)
			(stroke
				(width 0.1)
				(type default)
			)
			(layer "F.Fab")
		)
		(fp_poly
			(pts
				(xy -3.60172 -0.719328) (xy -3.60172 -1.344168) (xy -3.048 -1.016)
			)
			(stroke
				(width 0)
				(type default)
			)
			(fill yes)
			(layer "F.Fab")
		)
		(pad "1" smd rect
			(at -2.232406 -0.975106 270)
			(size 0.3556 1.4224)
			(layers "F.Cu" "F.Mask" "F.Paste")
			(net "MB_P52V_I2C_EN")
		)
		(pad "2" smd rect
			(at -2.232406 -0.32512 270)
			(size 0.3556 1.4224)
			(layers "F.Cu" "F.Mask" "F.Paste")
			(net "SMB_P52V_PDB_SCL_R")
		)
		(pad "3" smd rect
			(at -2.232406 0.32512 270)
			(size 0.3556 1.4224)
			(layers "F.Cu" "F.Mask" "F.Paste")
			(net "SMB_P52V_SCL")
		)
		(pad "4" smd rect
			(at -2.232406 0.975106 270)
			(size 0.3556 1.4224)
			(layers "F.Cu" "F.Mask" "F.Paste")
			(net "GND")
		)
		(pad "5" smd rect
			(at 2.232406 0.975106 270)
			(size 0.3556 1.4224)
			(layers "F.Cu" "F.Mask" "F.Paste")
			(net "NC_U2_READY")
		)
		(pad "6" smd rect
			(at 2.232406 0.32512 270)
			(size 0.3556 1.4224)
			(layers "F.Cu" "F.Mask" "F.Paste")
			(net "SMB_P52V_SDA")
		)
		(pad "7" smd rect
			(at 2.232406 -0.32512 270)
			(size 0.3556 1.4224)
			(layers "F.Cu" "F.Mask" "F.Paste")
			(net "SMB_P52V_PDB_SDA_R")
		)
		(pad "8" smd rect
			(at 2.232406 -0.975106 270)
			(size 0.3556 1.4224)
			(layers "F.Cu" "F.Mask" "F.Paste")
			(net "P3V3_AUX")
		)
	)
	(footprint ""
		(layer "F.Cu")
		(at 416.3314 -48.514)
		(property "Reference" "U29"
			(at -0.74803 -3.2385 90)
			(unlocked yes)
			(layer "F.SilkS")
			(effects
				(font
					(size 0.7874 0.5842)
					(thickness 0.1524)
				)
				(justify left)
			)
		)
		(property "Value" ""
			(at 0 0 0)
			(layer "F.Fab")
			(effects
				(font
					(size 1.27 1.27)
				)
			)
		)
		(duplicate_pad_numbers_are_jumpers no)
		(fp_line
			(start -1.603248 -1.500124)
			(end 1.603248 -1.500124)
			(stroke
				(width 0.1524)
				(type default)
			)
			(layer "F.SilkS")
		)
		(fp_line
			(start -1.603248 1.500124)
			(end -1.603248 -1.500124)
			(stroke
				(width 0.1524)
				(type default)
			)
			(layer "F.SilkS")
		)
		(fp_line
			(start 1.603248 -1.500124)
			(end 1.603248 1.500124)
			(stroke
				(width 0.1524)
				(type default)
			)
			(layer "F.SilkS")
		)
		(fp_line
			(start 1.603248 1.500124)
			(end -1.603248 1.500124)
			(stroke
				(width 0.1524)
				(type default)
			)
			(layer "F.SilkS")
		)
		(fp_line
			(start -1.249934 -1.169924)
			(end -1.249934 -0.729996)
			(stroke
				(width 0.1)
				(type default)
			)
			(layer "F.Fab")
		)
		(fp_line
			(start -1.249934 -0.729996)
			(end -0.6985 -0.729996)
			(stroke
				(width 0.1)
				(type default)
			)
			(layer "F.Fab")
		)
		(fp_line
			(start -1.249934 0.729996)
			(end -1.249934 1.169924)
			(stroke
				(width 0.1)
				(type default)
			)
			(layer "F.Fab")
		)
		(fp_line
			(start -1.249934 1.169924)
			(end -0.700024 1.169924)
			(stroke
				(width 0.1)
				(type default)
			)
			(layer "F.Fab")
		)
		(fp_line
			(start -0.700024 -1.500124)
			(end -0.700024 -1.169924)
			(stroke
				(width 0.1)
				(type default)
			)
			(layer "F.Fab")
		)
		(fp_line
			(start -0.700024 -1.169924)
			(end -1.249934 -1.169924)
			(stroke
				(width 0.1)
				(type default)
			)
			(layer "F.Fab")
		)
		(fp_line
			(start -0.700024 1.169924)
			(end -0.700024 1.500124)
			(stroke
				(width 0.1)
				(type default)
			)
			(layer "F.Fab")
		)
		(fp_line
			(start -0.700024 1.500124)
			(end 0.700024 1.500124)
			(stroke
				(width 0.1)
				(type default)
			)
			(layer "F.Fab")
		)
		(fp_line
			(start -0.6985 -0.729996)
			(end -0.6985 0.729996)
			(stroke
				(width 0.1)
				(type default)
			)
			(layer "F.Fab")
		)
		(fp_line
			(start -0.6985 0.729996)
			(end -1.249934 0.729996)
			(stroke
				(width 0.1)
				(type default)
			)
			(layer "F.Fab")
		)
		(fp_line
			(start 0.700024 -1.500124)
			(end -0.700024 -1.500124)
			(stroke
				(width 0.1)
				(type default)
			)
			(layer "F.Fab")
		)
		(fp_line
			(start 0.700024 -0.219964)
			(end 0.700024 -1.500124)
			(stroke
				(width 0.1)
				(type default)
			)
			(layer "F.Fab")
		)
		(fp_line
			(start 0.700024 0.219964)
			(end 1.249934 0.219964)
			(stroke
				(width 0.1)
				(type default)
			)
			(layer "F.Fab")
		)
		(fp_line
			(start 0.700024 1.500124)
			(end 0.700024 0.219964)
			(stroke
				(width 0.1)
				(type default)
			)
			(layer "F.Fab")
		)
		(fp_line
			(start 1.249934 -0.219964)
			(end 0.700024 -0.219964)
			(stroke
				(width 0.1)
				(type default)
			)
			(layer "F.Fab")
		)
		(fp_line
			(start 1.249934 0.219964)
			(end 1.249934 -0.219964)
			(stroke
				(width 0.1)
				(type default)
			)
			(layer "F.Fab")
		)
		(fp_rect
			(start -0.700024 1.500124)
			(end 0.700024 -1.500124)
			(stroke
				(width 0)
				(type default)
			)
			(fill no)
			(layer "F.Fab")
		)
		(pad "D" smd rect
			(at 0.999998 0 270)
			(size 0.8128 0.9144)
			(layers "F.Cu" "F.Mask" "F.Paste")
			(net "PWRGD_P52V_HS1_4287_PG")
		)
		(pad "G" smd rect
			(at -0.999998 -0.94996 270)
			(size 0.8128 0.9144)
			(layers "F.Cu" "F.Mask" "F.Paste")
			(net "PWRGD_P52V_HS1_4287_PG_R_N")
		)
		(pad "S" smd rect
			(at -0.999998 0.94996 270)
			(size 0.8128 0.9144)
			(layers "F.Cu" "F.Mask" "F.Paste")
			(net "GND")
		)
	)
	(footprint ""
		(layer "F.Cu")
		(at 406.146 -33.274 180)
		(property "Reference" "R44"
			(at 0 0 180)
			(layer "F.SilkS")
			(hide yes)
			(effects
				(font
					(size 1.27 1.27)
				)
			)
		)
		(property "Value" ""
			(at 0 0 180)
			(layer "F.Fab")
			(effects
				(font
					(size 1.27 1.27)
				)
			)
		)
		(duplicate_pad_numbers_are_jumpers no)
		(fp_line
			(start 2.234946 0.9271)
			(end -2.234946 0.9271)
			(stroke
				(width 0.1524)
				(type default)
			)
			(layer "F.SilkS")
		)
		(fp_line
			(start 2.234946 -0.9271)
			(end 2.234946 0.9271)
			(stroke
				(width 0.1524)
				(type default)
			)
			(layer "F.SilkS")
		)
		(fp_line
			(start -2.234946 0.9271)
			(end -2.234946 -0.9271)
			(stroke
				(width 0.1524)
				(type default)
			)
			(layer "F.SilkS")
		)
		(fp_line
			(start -2.234946 -0.9271)
			(end 2.234946 -0.9271)
			(stroke
				(width 0.1524)
				(type default)
			)
			(layer "F.SilkS")
		)
		(fp_line
			(start 1.575054 0.824992)
			(end 1.575054 -0.824992)
			(stroke
				(width 0.1)
				(type default)
			)
			(layer "F.Fab")
		)
		(fp_line
			(start 1.575054 -0.824992)
			(end -1.575054 -0.824992)
			(stroke
				(width 0.1)
				(type default)
			)
			(layer "F.Fab")
		)
		(fp_line
			(start -1.575054 0.824992)
			(end 1.575054 0.824992)
			(stroke
				(width 0.1)
				(type default)
			)
			(layer "F.Fab")
		)
		(fp_line
			(start -1.575054 -0.824992)
			(end -1.575054 0.824992)
			(stroke
				(width 0.1)
				(type default)
			)
			(layer "F.Fab")
		)
		(pad "1" smd rect
			(at -1.599946 0 180)
			(size 1.016 1.6002)
			(layers "F.Cu" "F.Mask" "F.Paste")
			(net "LED_D1_R3")
		)
		(pad "2" smd rect
			(at 1.599946 0 180)
			(size 1.016 1.6002)
			(layers "F.Cu" "F.Mask" "F.Paste")
			(net "LED_D1_R4")
		)
	)
	(footprint ""
		(layer "F.Cu")
		(at 323.13626 -74.6506 180)
		(property "Reference" "PQ32"
			(at -9.628886 -3.917188 0)
			(unlocked yes)
			(layer "F.SilkS")
			(effects
				(font
					(size 0.7874 0.5842)
					(thickness 0.1524)
				)
				(justify left)
			)
		)
		(property "Value" ""
			(at 0 0 180)
			(layer "F.Fab")
			(effects
				(font
					(size 1.27 1.27)
				)
			)
		)
		(duplicate_pad_numbers_are_jumpers no)
		(fp_line
			(start 7.649972 4.99999)
			(end 7.649972 -4.99999)
			(stroke
				(width 0.1524)
				(type default)
			)
			(layer "F.SilkS")
		)
		(fp_line
			(start 7.649972 -4.99999)
			(end 7.630414 -4.99999)
			(stroke
				(width 0.1524)
				(type default)
			)
			(layer "F.SilkS")
		)
		(fp_line
			(start 7.630414 4.99999)
			(end 7.649972 4.99999)
			(stroke
				(width 0.1524)
				(type default)
			)
			(layer "F.SilkS")
		)
		(fp_line
			(start 5.115814 -4.99999)
			(end -7.649972 -4.99999)
			(stroke
				(width 0.1524)
				(type default)
			)
			(layer "F.SilkS")
		)
		(fp_line
			(start -7.649972 4.99999)
			(end 5.115814 4.99999)
			(stroke
				(width 0.1524)
				(type default)
			)
			(layer "F.SilkS")
		)
		(fp_line
			(start -7.649972 3.3274)
			(end -7.649972 4.99999)
			(stroke
				(width 0.1524)
				(type default)
			)
			(layer "F.SilkS")
		)
		(fp_line
			(start -7.649972 -1.7526)
			(end -7.649972 1.7526)
			(stroke
				(width 0.1524)
				(type default)
			)
			(layer "F.SilkS")
		)
		(fp_line
			(start -7.649972 -4.99999)
			(end -7.649972 -3.3274)
			(stroke
				(width 0.1524)
				(type default)
			)
			(layer "F.SilkS")
		)
		(fp_line
			(start 7.649972 4.99999)
			(end 7.649972 -4.99999)
			(stroke
				(width 0.1)
				(type default)
			)
			(layer "F.Fab")
		)
		(fp_line
			(start 7.649972 -4.99999)
			(end -7.649972 -4.99999)
			(stroke
				(width 0.1)
				(type default)
			)
			(layer "F.Fab")
		)
		(fp_line
			(start -7.649972 4.99999)
			(end 7.649972 4.99999)
			(stroke
				(width 0.1)
				(type default)
			)
			(layer "F.Fab")
		)
		(fp_line
			(start -7.649972 -4.99999)
			(end -7.649972 4.99999)
			(stroke
				(width 0.1)
				(type default)
			)
			(layer "F.Fab")
		)
		(pad "D" smd circle
			(at 2.15011 0 180)
			(size 0 0)
			(layers "F.Cu" "F.Mask" "F.Paste")
			(net "P52V_HS1_DRAIN_1")
		)
		(pad "G" smd rect
			(at -7.050024 -2.54 90)
			(size 1.3208 3.0988)
			(layers "F.Cu" "F.Mask" "F.Paste")
			(net "P52V_HS1_GATE1")
		)
		(pad "S" smd rect
			(at -7.050024 2.54 90)
			(size 1.3208 3.0988)
			(layers "F.Cu" "F.Mask" "F.Paste")
			(net "P52V_HS1")
		)
		(zone
			(layer "F.Cu")
			(hatch none 0.5)
			(connect_pads
				(clearance 0)
			)
			(min_thickness 0.25)
			(keepout
				(tracks not_allowed)
				(vias allowed)
				(pads allowed)
				(copperpour not_allowed)
				(footprints allowed)
			)
			(placement
				(enabled no)
				(sheetname "")
			)
			(fill
				(thermal_gap 0.5)
				(thermal_bridge_width 0.5)
				(island_removal_mode 0)
			)
			(polygon
				(pts
					(xy 317.95466 -69.6722) (xy 330.78166 -69.6722) (xy 330.78166 -71.3994) (xy 328.57186 -71.3994)
					(xy 328.57186 -72.8218) (xy 330.78166 -72.8218) (xy 330.78166 -76.4794) (xy 328.57186 -76.4794)
					(xy 328.57186 -77.9018) (xy 330.78166 -77.9018) (xy 330.78166 -79.629) (xy 317.95466 -79.629) (xy 317.95466 -78.4606)
					(xy 324.15226 -78.4606) (xy 324.15226 -70.8406) (xy 317.95466 -70.8406)
				)
			)
		)
	)
	(footprint ""
		(layer "F.Cu")
		(at 124.483876 -52.0954)
		(property "Reference" "PQ40"
			(at 8.913114 -3.609848 0)
			(unlocked yes)
			(layer "F.SilkS")
			(effects
				(font
					(size 0.7874 0.5842)
					(thickness 0.1524)
				)
				(justify left)
			)
		)
		(property "Value" ""
			(at 0 0 0)
			(layer "F.Fab")
			(effects
				(font
					(size 1.27 1.27)
				)
			)
		)
		(duplicate_pad_numbers_are_jumpers no)
		(fp_line
			(start -7.649972 -4.99999)
			(end -7.649972 -3.3274)
			(stroke
				(width 0.1524)
				(type default)
			)
			(layer "F.SilkS")
		)
		(fp_line
			(start -7.649972 -1.7526)
			(end -7.649972 1.7526)
			(stroke
				(width 0.1524)
				(type default)
			)
			(layer "F.SilkS")
		)
		(fp_line
			(start -7.649972 3.3274)
			(end -7.649972 4.99999)
			(stroke
				(width 0.1524)
				(type default)
			)
			(layer "F.SilkS")
		)
		(fp_line
			(start -7.649972 4.99999)
			(end 5.115814 4.99999)
			(stroke
				(width 0.1524)
				(type default)
			)
			(layer "F.SilkS")
		)
		(fp_line
			(start 5.115814 -4.99999)
			(end -7.649972 -4.99999)
			(stroke
				(width 0.1524)
				(type default)
			)
			(layer "F.SilkS")
		)
		(fp_line
			(start 7.630414 4.99999)
			(end 7.649972 4.99999)
			(stroke
				(width 0.1524)
				(type default)
			)
			(layer "F.SilkS")
		)
		(fp_line
			(start 7.649972 -4.99999)
			(end 7.630414 -4.99999)
			(stroke
				(width 0.1524)
				(type default)
			)
			(layer "F.SilkS")
		)
		(fp_line
			(start 7.649972 4.99999)
			(end 7.649972 -4.99999)
			(stroke
				(width 0.1524)
				(type default)
			)
			(layer "F.SilkS")
		)
		(fp_line
			(start -7.649972 -4.99999)
			(end -7.649972 4.99999)
			(stroke
				(width 0.1)
				(type default)
			)
			(layer "F.Fab")
		)
		(fp_line
			(start -7.649972 4.99999)
			(end 7.649972 4.99999)
			(stroke
				(width 0.1)
				(type default)
			)
			(layer "F.Fab")
		)
		(fp_line
			(start 7.649972 -4.99999)
			(end -7.649972 -4.99999)
			(stroke
				(width 0.1)
				(type default)
			)
			(layer "F.Fab")
		)
		(fp_line
			(start 7.649972 4.99999)
			(end 7.649972 -4.99999)
			(stroke
				(width 0.1)
				(type default)
			)
			(layer "F.Fab")
		)
		(pad "D" smd circle
			(at 2.15011 0)
			(size 0 0)
			(layers "F.Cu" "F.Mask" "F.Paste")
			(net "P52V_HS2_DRAIN_1")
		)
		(pad "G" smd rect
			(at -7.050024 -2.54 270)
			(size 1.3208 3.0988)
			(layers "F.Cu" "F.Mask" "F.Paste")
			(net "P52V_HS2_GATE3")
		)
		(pad "S" smd rect
			(at -7.050024 2.54 270)
			(size 1.3208 3.0988)
			(layers "F.Cu" "F.Mask" "F.Paste")
			(net "P52V_HS2")
		)
		(zone
			(layer "F.Cu")
			(hatch none 0.5)
			(connect_pads
				(clearance 0)
			)
			(min_thickness 0.25)
			(keepout
				(tracks not_allowed)
				(vias allowed)
				(pads allowed)
				(copperpour not_allowed)
				(footprints allowed)
			)
			(placement
				(enabled no)
				(sheetname "")
			)
			(fill
				(thermal_gap 0.5)
				(thermal_bridge_width 0.5)
				(island_removal_mode 0)
			)
			(polygon
				(pts
					(xy 129.665476 -57.0738) (xy 116.838476 -57.0738) (xy 116.838476 -55.3466) (xy 119.048276 -55.3466)
					(xy 119.048276 -53.9242) (xy 116.838476 -53.9242) (xy 116.838476 -50.2666) (xy 119.048276 -50.2666)
					(xy 119.048276 -48.8442) (xy 116.838476 -48.8442) (xy 116.838476 -47.117) (xy 129.665476 -47.117)
					(xy 129.665476 -48.2854) (xy 123.467876 -48.2854) (xy 123.467876 -55.9054) (xy 129.665476 -55.9054)
				)
			)
		)
	)
)
